(kicad_pcb
	(version 20260206)
	(generator "pcbnew")
	(generator_version "10.0")
	(general
		(thickness 1.6)
		(legacy_teardrops no)
	)
	(paper "A4")
	(title_block
		(title "04192023_DAF0TMB3IC0_F0TG_MB_C_brd_V02_OCP.brd")
		(comment 1 "Grand Teton / footprints 687-693 of 8354")
	)
	(layers
		(0 "F.Cu" signal "TOP")
		(4 "In1.Cu" signal "GND")
		(6 "In2.Cu" signal "IN1")
		(8 "In3.Cu" signal "GND1")
		(10 "In4.Cu" signal "IN2")
		(12 "In5.Cu" signal "GND2")
		(14 "In6.Cu" signal "IN3")
		(16 "In7.Cu" signal "GND3")
		(18 "In8.Cu" signal "VCC")
		(20 "In9.Cu" signal "VCC1")
		(22 "In10.Cu" signal "GND4")
		(24 "In11.Cu" signal "IN4")
		(26 "In12.Cu" signal "GND5")
		(28 "In13.Cu" signal "IN5")
		(30 "In14.Cu" signal "GND6")
		(32 "In15.Cu" signal "IN6")
		(34 "In16.Cu" signal "GND7")
		(2 "B.Cu" signal "BOTTOM")
		(9 "F.Adhes" user "F.Adhesive")
		(11 "B.Adhes" user "B.Adhesive")
		(13 "F.Paste" user "Package Geometry/Pastemask Top")
		(15 "B.Paste" user "Package Geometry/Pastemask Bottom")
		(5 "F.SilkS" user "Ref Des/Silkscreen Top")
		(7 "B.SilkS" user "Ref Des/Silkscreen Bottom")
		(1 "F.Mask" user "Board Geometry/Soldermask Top")
		(3 "B.Mask" user "Board Geometry/Soldermask Bottom")
		(17 "Dwgs.User" user "User.Drawings")
		(19 "Cmts.User" user "User.Comments")
		(21 "Eco1.User" user "User.Eco1")
		(23 "Eco2.User" user "User.Eco2")
		(25 "Edge.Cuts" user "Board Geometry/Outline")
		(27 "Margin" user)
		(31 "F.CrtYd" user "Package Geometry/Place Bound Top")
		(29 "B.CrtYd" user "Package Geometry/Place Bound Bottom")
		(35 "F.Fab" user "Ref Des/Assembly Top")
		(33 "B.Fab" user "Ref Des/Assembly Bottom")
	)
	(footprint ""
		(layer "F.Cu")
		(at 422.180766 -404.0124 -90)
		(property "Reference" "R1081"
			(at 0 0 270)
			(layer "F.SilkS")
			(hide yes)
			(effects
				(font
					(size 1.27 1.27)
				)
			)
		)
		(property "Value" ""
			(at 0 0 270)
			(layer "F.Fab")
			(effects
				(font
					(size 1.27 1.27)
				)
			)
		)
		(duplicate_pad_numbers_are_jumpers no)
		(fp_line
			(start -0.32512 0.175006)
			(end -0.32512 -0.175006)
			(stroke
				(width 0.1)
				(type default)
			)
			(layer "F.Fab")
		)
		(fp_line
			(start 0.32512 0.175006)
			(end -0.32512 0.175006)
			(stroke
				(width 0.1)
				(type default)
			)
			(layer "F.Fab")
		)
		(fp_line
			(start -0.32512 -0.175006)
			(end 0.32512 -0.175006)
			(stroke
				(width 0.1)
				(type default)
			)
			(layer "F.Fab")
		)
		(fp_line
			(start 0.32512 -0.175006)
			(end 0.32512 0.175006)
			(stroke
				(width 0.1)
				(type default)
			)
			(layer "F.Fab")
		)
		(pad "1" smd rect
			(at -0.2667 0 270)
			(size 0.3048 0.381)
			(layers "F.Cu" "F.Mask" "F.Paste")
			(net "P1V8_CPU0_RT_1D")
		)
		(pad "2" smd rect
			(at 0.2667 0 90)
			(size 0.3048 0.381)
			(layers "F.Cu" "F.Mask" "F.Paste")
			(net "RT_CPU0_P2_VQPS")
		)
	)
	(footprint ""
		(layer "F.Cu")
		(at 24.057102 -351.621598 90)
		(property "Reference" "PR340"
			(at 0 0 90)
			(layer "F.SilkS")
			(hide yes)
			(effects
				(font
					(size 1.27 1.27)
				)
			)
		)
		(property "Value" ""
			(at 0 0 90)
			(layer "F.Fab")
			(effects
				(font
					(size 1.27 1.27)
				)
			)
		)
		(duplicate_pad_numbers_are_jumpers no)
		(fp_line
			(start 0.7874 -0.4064)
			(end 0.7874 0.4064)
			(stroke
				(width 0.1524)
				(type default)
			)
			(layer "F.SilkS")
		)
		(fp_line
			(start -0.7874 -0.4064)
			(end 0.7874 -0.4064)
			(stroke
				(width 0.1524)
				(type default)
			)
			(layer "F.SilkS")
		)
		(fp_line
			(start 0.7874 0.4064)
			(end -0.7874 0.4064)
			(stroke
				(width 0.1524)
				(type default)
			)
			(layer "F.SilkS")
		)
		(fp_line
			(start -0.7874 0.4064)
			(end -0.7874 -0.4064)
			(stroke
				(width 0.1524)
				(type default)
			)
			(layer "F.SilkS")
		)
		(fp_line
			(start -0.12065 -0.305054)
			(end -0.12065 -0.2794)
			(stroke
				(width 0.1)
				(type default)
			)
			(layer "F.Fab")
		)
		(fp_line
			(start -0.67945 -0.305054)
			(end -0.12065 -0.305054)
			(stroke
				(width 0.1)
				(type default)
			)
			(layer "F.Fab")
		)
		(fp_line
			(start 0.67945 -0.3048)
			(end 0.67945 0.3048)
			(stroke
				(width 0.1)
				(type default)
			)
			(layer "F.Fab")
		)
		(fp_line
			(start 0.12065 -0.3048)
			(end 0.67945 -0.3048)
			(stroke
				(width 0.1)
				(type default)
			)
			(layer "F.Fab")
		)
		(fp_line
			(start 0.12065 -0.2794)
			(end 0.12065 -0.3048)
			(stroke
				(width 0.1)
				(type default)
			)
			(layer "F.Fab")
		)
		(fp_line
			(start -0.12065 -0.2794)
			(end 0.12065 -0.2794)
			(stroke
				(width 0.1)
				(type default)
			)
			(layer "F.Fab")
		)
		(fp_line
			(start 0.120396 0.2794)
			(end -0.12065 0.2794)
			(stroke
				(width 0.1)
				(type default)
			)
			(layer "F.Fab")
		)
		(fp_line
			(start -0.12065 0.2794)
			(end -0.12065 0.3048)
			(stroke
				(width 0.1)
				(type default)
			)
			(layer "F.Fab")
		)
		(fp_line
			(start 0.67945 0.3048)
			(end 0.120396 0.3048)
			(stroke
				(width 0.1)
				(type default)
			)
			(layer "F.Fab")
		)
		(fp_line
			(start 0.120396 0.3048)
			(end 0.120396 0.2794)
			(stroke
				(width 0.1)
				(type default)
			)
			(layer "F.Fab")
		)
		(fp_line
			(start -0.12065 0.3048)
			(end -0.67945 0.3048)
			(stroke
				(width 0.1)
				(type default)
			)
			(layer "F.Fab")
		)
		(fp_line
			(start -0.67945 0.3048)
			(end -0.67945 -0.305054)
			(stroke
				(width 0.1)
				(type default)
			)
			(layer "F.Fab")
		)
		(pad "1" smd circle
			(at -0.40005 0 90)
			(size 0 0)
			(layers "F.Cu" "F.Mask" "F.Paste")
			(net "PVDDCR_CPU1_P1_PVCC")
		)
		(pad "2" smd circle
			(at 0.40005 0 90)
			(size 0 0)
			(layers "F.Cu" "F.Mask" "F.Paste")
			(net "P5V_AUX")
		)
	)
	(footprint ""
		(layer "F.Cu")
		(at 414.325562 -362.804964 180)
		(property "Reference" "PR128"
			(at 0 0 180)
			(layer "F.SilkS")
			(hide yes)
			(effects
				(font
					(size 1.27 1.27)
				)
			)
		)
		(property "Value" ""
			(at 0 0 180)
			(layer "F.Fab")
			(effects
				(font
					(size 1.27 1.27)
				)
			)
		)
		(duplicate_pad_numbers_are_jumpers no)
		(fp_line
			(start 0.7874 0.4064)
			(end -0.7874 0.4064)
			(stroke
				(width 0.1524)
				(type default)
			)
			(layer "F.SilkS")
		)
		(fp_line
			(start 0.7874 -0.4064)
			(end 0.7874 0.4064)
			(stroke
				(width 0.1524)
				(type default)
			)
			(layer "F.SilkS")
		)
		(fp_line
			(start -0.7874 0.4064)
			(end -0.7874 -0.4064)
			(stroke
				(width 0.1524)
				(type default)
			)
			(layer "F.SilkS")
		)
		(fp_line
			(start -0.7874 -0.4064)
			(end 0.7874 -0.4064)
			(stroke
				(width 0.1524)
				(type default)
			)
			(layer "F.SilkS")
		)
		(fp_line
			(start 0.67945 0.3048)
			(end 0.120396 0.3048)
			(stroke
				(width 0.1)
				(type default)
			)
			(layer "F.Fab")
		)
		(fp_line
			(start 0.67945 -0.3048)
			(end 0.67945 0.3048)
			(stroke
				(width 0.1)
				(type default)
			)
			(layer "F.Fab")
		)
		(fp_line
			(start 0.12065 -0.2794)
			(end 0.12065 -0.3048)
			(stroke
				(width 0.1)
				(type default)
			)
			(layer "F.Fab")
		)
		(fp_line
			(start 0.12065 -0.3048)
			(end 0.67945 -0.3048)
			(stroke
				(width 0.1)
				(type default)
			)
			(layer "F.Fab")
		)
		(fp_line
			(start 0.120396 0.3048)
			(end 0.120396 0.2794)
			(stroke
				(width 0.1)
				(type default)
			)
			(layer "F.Fab")
		)
		(fp_line
			(start 0.120396 0.2794)
			(end -0.12065 0.2794)
			(stroke
				(width 0.1)
				(type default)
			)
			(layer "F.Fab")
		)
		(fp_line
			(start -0.12065 0.3048)
			(end -0.67945 0.3048)
			(stroke
				(width 0.1)
				(type default)
			)
			(layer "F.Fab")
		)
		(fp_line
			(start -0.12065 0.2794)
			(end -0.12065 0.3048)
			(stroke
				(width 0.1)
				(type default)
			)
			(layer "F.Fab")
		)
		(fp_line
			(start -0.12065 -0.2794)
			(end 0.12065 -0.2794)
			(stroke
				(width 0.1)
				(type default)
			)
			(layer "F.Fab")
		)
		(fp_line
			(start -0.12065 -0.305054)
			(end -0.12065 -0.2794)
			(stroke
				(width 0.1)
				(type default)
			)
			(layer "F.Fab")
		)
		(fp_line
			(start -0.67945 0.3048)
			(end -0.67945 -0.305054)
			(stroke
				(width 0.1)
				(type default)
			)
			(layer "F.Fab")
		)
		(fp_line
			(start -0.67945 -0.305054)
			(end -0.12065 -0.305054)
			(stroke
				(width 0.1)
				(type default)
			)
			(layer "F.Fab")
		)
		(pad "1" smd circle
			(at -0.40005 0 180)
			(size 0 0)
			(layers "F.Cu" "F.Mask" "F.Paste")
			(net "PVDD11_S3_P0_RESET_N_R")
		)
		(pad "2" smd circle
			(at 0.40005 0 180)
			(size 0 0)
			(layers "F.Cu" "F.Mask" "F.Paste")
			(net "PVDD18_S5_P0")
		)
	)
	(footprint ""
		(layer "F.Cu")
		(at 137.186924 -167.9702 -90)
		(property "Reference" "PC338"
			(at 0 0 270)
			(layer "F.SilkS")
			(hide yes)
			(effects
				(font
					(size 1.27 1.27)
				)
			)
		)
		(property "Value" ""
			(at 0 0 270)
			(layer "F.Fab")
			(effects
				(font
					(size 1.27 1.27)
				)
			)
		)
		(duplicate_pad_numbers_are_jumpers no)
		(fp_line
			(start -0.7874 0.4064)
			(end -0.7874 -0.4064)
			(stroke
				(width 0.1524)
				(type default)
			)
			(layer "F.SilkS")
		)
		(fp_line
			(start 0.7874 0.4064)
			(end -0.7874 0.4064)
			(stroke
				(width 0.1524)
				(type default)
			)
			(layer "F.SilkS")
		)
		(fp_line
			(start -0.7874 -0.4064)
			(end 0.7874 -0.4064)
			(stroke
				(width 0.1524)
				(type default)
			)
			(layer "F.SilkS")
		)
		(fp_line
			(start 0.7874 -0.4064)
			(end 0.7874 0.4064)
			(stroke
				(width 0.1524)
				(type default)
			)
			(layer "F.SilkS")
		)
		(fp_line
			(start -0.67945 0.3048)
			(end -0.67945 -0.305054)
			(stroke
				(width 0.1)
				(type default)
			)
			(layer "F.Fab")
		)
		(fp_line
			(start -0.12065 0.3048)
			(end -0.67945 0.3048)
			(stroke
				(width 0.1)
				(type default)
			)
			(layer "F.Fab")
		)
		(fp_line
			(start 0.120396 0.3048)
			(end 0.120396 0.2794)
			(stroke
				(width 0.1)
				(type default)
			)
			(layer "F.Fab")
		)
		(fp_line
			(start 0.67945 0.3048)
			(end 0.120396 0.3048)
			(stroke
				(width 0.1)
				(type default)
			)
			(layer "F.Fab")
		)
		(fp_line
			(start -0.12065 0.2794)
			(end -0.12065 0.3048)
			(stroke
				(width 0.1)
				(type default)
			)
			(layer "F.Fab")
		)
		(fp_line
			(start 0.120396 0.2794)
			(end -0.12065 0.2794)
			(stroke
				(width 0.1)
				(type default)
			)
			(layer "F.Fab")
		)
		(fp_line
			(start -0.12065 -0.2794)
			(end 0.12065 -0.2794)
			(stroke
				(width 0.1)
				(type default)
			)
			(layer "F.Fab")
		)
		(fp_line
			(start 0.12065 -0.2794)
			(end 0.12065 -0.3048)
			(stroke
				(width 0.1)
				(type default)
			)
			(layer "F.Fab")
		)
		(fp_line
			(start 0.12065 -0.3048)
			(end 0.67945 -0.3048)
			(stroke
				(width 0.1)
				(type default)
			)
			(layer "F.Fab")
		)
		(fp_line
			(start 0.67945 -0.3048)
			(end 0.67945 0.3048)
			(stroke
				(width 0.1)
				(type default)
			)
			(layer "F.Fab")
		)
		(fp_line
			(start -0.67945 -0.305054)
			(end -0.12065 -0.305054)
			(stroke
				(width 0.1)
				(type default)
			)
			(layer "F.Fab")
		)
		(fp_line
			(start -0.12065 -0.305054)
			(end -0.12065 -0.2794)
			(stroke
				(width 0.1)
				(type default)
			)
			(layer "F.Fab")
		)
		(pad "1" smd circle
			(at -0.40005 0 270)
			(size 0 0)
			(layers "F.Cu" "F.Mask" "F.Paste")
			(net "PVDDCR_SOC_P1")
		)
		(pad "2" smd circle
			(at 0.40005 0 270)
			(size 0 0)
			(layers "F.Cu" "F.Mask" "F.Paste")
			(net "GND")
		)
	)
	(footprint ""
		(layer "F.Cu")
		(at 167.132 -110.200948 180)
		(property "Reference" "R152"
			(at 0 0 180)
			(layer "F.SilkS")
			(hide yes)
			(effects
				(font
					(size 1.27 1.27)
				)
			)
		)
		(property "Value" ""
			(at 0 0 180)
			(layer "F.Fab")
			(effects
				(font
					(size 1.27 1.27)
				)
			)
		)
		(duplicate_pad_numbers_are_jumpers no)
		(fp_line
			(start 0.7874 0.4064)
			(end -0.7874 0.4064)
			(stroke
				(width 0.1524)
				(type default)
			)
			(layer "F.SilkS")
		)
		(fp_line
			(start 0.7874 -0.4064)
			(end 0.7874 0.4064)
			(stroke
				(width 0.1524)
				(type default)
			)
			(layer "F.SilkS")
		)
		(fp_line
			(start -0.7874 0.4064)
			(end -0.7874 -0.4064)
			(stroke
				(width 0.1524)
				(type default)
			)
			(layer "F.SilkS")
		)
		(fp_line
			(start -0.7874 -0.4064)
			(end 0.7874 -0.4064)
			(stroke
				(width 0.1524)
				(type default)
			)
			(layer "F.SilkS")
		)
		(fp_line
			(start 0.67945 0.3048)
			(end 0.120396 0.3048)
			(stroke
				(width 0.1)
				(type default)
			)
			(layer "F.Fab")
		)
		(fp_line
			(start 0.67945 -0.3048)
			(end 0.67945 0.3048)
			(stroke
				(width 0.1)
				(type default)
			)
			(layer "F.Fab")
		)
		(fp_line
			(start 0.12065 -0.2794)
			(end 0.12065 -0.3048)
			(stroke
				(width 0.1)
				(type default)
			)
			(layer "F.Fab")
		)
		(fp_line
			(start 0.12065 -0.3048)
			(end 0.67945 -0.3048)
			(stroke
				(width 0.1)
				(type default)
			)
			(layer "F.Fab")
		)
		(fp_line
			(start 0.120396 0.3048)
			(end 0.120396 0.2794)
			(stroke
				(width 0.1)
				(type default)
			)
			(layer "F.Fab")
		)
		(fp_line
			(start 0.120396 0.2794)
			(end -0.12065 0.2794)
			(stroke
				(width 0.1)
				(type default)
			)
			(layer "F.Fab")
		)
		(fp_line
			(start -0.12065 0.3048)
			(end -0.67945 0.3048)
			(stroke
				(width 0.1)
				(type default)
			)
			(layer "F.Fab")
		)
		(fp_line
			(start -0.12065 0.2794)
			(end -0.12065 0.3048)
			(stroke
				(width 0.1)
				(type default)
			)
			(layer "F.Fab")
		)
		(fp_line
			(start -0.12065 -0.2794)
			(end 0.12065 -0.2794)
			(stroke
				(width 0.1)
				(type default)
			)
			(layer "F.Fab")
		)
		(fp_line
			(start -0.12065 -0.305054)
			(end -0.12065 -0.2794)
			(stroke
				(width 0.1)
				(type default)
			)
			(layer "F.Fab")
		)
		(fp_line
			(start -0.67945 0.3048)
			(end -0.67945 -0.305054)
			(stroke
				(width 0.1)
				(type default)
			)
			(layer "F.Fab")
		)
		(fp_line
			(start -0.67945 -0.305054)
			(end -0.12065 -0.305054)
			(stroke
				(width 0.1)
				(type default)
			)
			(layer "F.Fab")
		)
		(pad "1" smd circle
			(at -0.40005 0 180)
			(size 0 0)
			(layers "F.Cu" "F.Mask" "F.Paste")
			(net "P12V_OCP_SFF_EN")
		)
		(pad "2" smd circle
			(at 0.40005 0 180)
			(size 0 0)
			(layers "F.Cu" "F.Mask" "F.Paste")
			(net "P12V_OCP_SFF_EN_R")
		)
	)
	(footprint ""
		(layer "F.Cu")
		(at 94.237302 -375.49963 -90)
		(property "Reference" "C721"
			(at 0 0 270)
			(layer "F.SilkS")
			(hide yes)
			(effects
				(font
					(size 1.27 1.27)
				)
			)
		)
		(property "Value" ""
			(at 0 0 270)
			(layer "F.Fab")
			(effects
				(font
					(size 1.27 1.27)
				)
			)
		)
		(duplicate_pad_numbers_are_jumpers no)
		(fp_line
			(start -0.299974 0.150114)
			(end -0.299974 -0.150114)
			(stroke
				(width 0.1)
				(type default)
			)
			(layer "F.Fab")
		)
		(fp_line
			(start 0.299974 0.150114)
			(end -0.299974 0.150114)
			(stroke
				(width 0.1)
				(type default)
			)
			(layer "F.Fab")
		)
		(fp_line
			(start -0.299974 -0.150114)
			(end 0.299974 -0.150114)
			(stroke
				(width 0.1)
				(type default)
			)
			(layer "F.Fab")
		)
		(fp_line
			(start 0.299974 -0.150114)
			(end 0.299974 0.150114)
			(stroke
				(width 0.1)
				(type default)
			)
			(layer "F.Fab")
		)
		(pad "1" smd rect
			(at -0.2667 0 270)
			(size 0.3048 0.381)
			(layers "F.Cu" "F.Mask" "F.Paste")
			(net "P5E_CPU1_P1_TX_C_DP<10>")
		)
		(pad "2" smd rect
			(at 0.2667 0 270)
			(size 0.3048 0.381)
			(layers "F.Cu" "F.Mask" "F.Paste")
			(net "P5E_CPU1_P1_TX_DP<10>")
		)
	)
	(footprint ""
		(layer "F.Cu")
		(at 203.2 -99.695)
		(property "Reference" "R8085"
			(at 0 0 0)
			(layer "F.SilkS")
			(hide yes)
			(effects
				(font
					(size 1.27 1.27)
				)
			)
		)
		(property "Value" ""
			(at 0 0 0)
			(layer "F.Fab")
			(effects
				(font
					(size 1.27 1.27)
				)
			)
		)
		(duplicate_pad_numbers_are_jumpers no)
		(fp_line
			(start -0.7874 -0.4064)
			(end 0.7874 -0.4064)
			(stroke
				(width 0.1524)
				(type default)
			)
			(layer "F.SilkS")
		)
		(fp_line
			(start -0.7874 0.4064)
			(end -0.7874 -0.4064)
			(stroke
				(width 0.1524)
				(type default)
			)
			(layer "F.SilkS")
		)
		(fp_line
			(start 0.7874 -0.4064)
			(end 0.7874 0.4064)
			(stroke
				(width 0.1524)
				(type default)
			)
			(layer "F.SilkS")
		)
		(fp_line
			(start 0.7874 0.4064)
			(end -0.7874 0.4064)
			(stroke
				(width 0.1524)
				(type default)
			)
			(layer "F.SilkS")
		)
		(fp_line
			(start -0.67945 -0.305054)
			(end -0.12065 -0.305054)
			(stroke
				(width 0.1)
				(type default)
			)
			(layer "F.Fab")
		)
		(fp_line
			(start -0.67945 0.3048)
			(end -0.67945 -0.305054)
			(stroke
				(width 0.1)
				(type default)
			)
			(layer "F.Fab")
		)
		(fp_line
			(start -0.12065 -0.305054)
			(end -0.12065 -0.2794)
			(stroke
				(width 0.1)
				(type default)
			)
			(layer "F.Fab")
		)
		(fp_line
			(start -0.12065 -0.2794)
			(end 0.12065 -0.2794)
			(stroke
				(width 0.1)
				(type default)
			)
			(layer "F.Fab")
		)
		(fp_line
			(start -0.12065 0.2794)
			(end -0.12065 0.3048)
			(stroke
				(width 0.1)
				(type default)
			)
			(layer "F.Fab")
		)
		(fp_line
			(start -0.12065 0.3048)
			(end -0.67945 0.3048)
			(stroke
				(width 0.1)
				(type default)
			)
			(layer "F.Fab")
		)
		(fp_line
			(start 0.120396 0.2794)
			(end -0.12065 0.2794)
			(stroke
				(width 0.1)
				(type default)
			)
			(layer "F.Fab")
		)
		(fp_line
			(start 0.120396 0.3048)
			(end 0.120396 0.2794)
			(stroke
				(width 0.1)
				(type default)
			)
			(layer "F.Fab")
		)
		(fp_line
			(start 0.12065 -0.3048)
			(end 0.67945 -0.3048)
			(stroke
				(width 0.1)
				(type default)
			)
			(layer "F.Fab")
		)
		(fp_line
			(start 0.12065 -0.2794)
			(end 0.12065 -0.3048)
			(stroke
				(width 0.1)
				(type default)
			)
			(layer "F.Fab")
		)
		(fp_line
			(start 0.67945 -0.3048)
			(end 0.67945 0.3048)
			(stroke
				(width 0.1)
				(type default)
			)
			(layer "F.Fab")
		)
		(fp_line
			(start 0.67945 0.3048)
			(end 0.120396 0.3048)
			(stroke
				(width 0.1)
				(type default)
			)
			(layer "F.Fab")
		)
		(pad "1" smd circle
			(at -0.40005 0)
			(size 0 0)
			(layers "F.Cu" "F.Mask" "F.Paste")
			(net "P3V3_AUX")
		)
		(pad "2" smd circle
			(at 0.40005 0)
			(size 0 0)
			(layers "F.Cu" "F.Mask" "F.Paste")
			(net "PWRGD_CHGL_CPU0_R1")
		)
	)
)
